(kicad_pcb
	(version 20260206)
	(generator "pcbnew")
	(generator_version "10.0")
	(general
		(thickness 1.6)
		(legacy_teardrops no)
	)
	(paper "A4")
	(title_block
		(title "01162023_DA0F0TEBIF0_F0T_Expander_BD_F_brd_V02_OCP.brd")
		(comment 1 "Grand Teton / footprints 3573-3578 of 9728")
	)
	(layers
		(0 "F.Cu" signal "TOP")
		(4 "In1.Cu" signal "GND")
		(6 "In2.Cu" signal "VCC")
		(8 "In3.Cu" signal "VCC1")
		(10 "In4.Cu" signal "GND1")
		(12 "In5.Cu" signal "IN1")
		(14 "In6.Cu" signal "GND2")
		(16 "In7.Cu" signal "IN2")
		(18 "In8.Cu" signal "GND3")
		(20 "In9.Cu" signal "IN3")
		(22 "In10.Cu" signal "GND4")
		(24 "In11.Cu" signal "IN4")
		(26 "In12.Cu" signal "GND5")
		(28 "In13.Cu" signal "IN5")
		(30 "In14.Cu" signal "GND6")
		(32 "In15.Cu" signal "IN6")
		(34 "In16.Cu" signal "GND7")
		(2 "B.Cu" signal "BOTTOM")
		(9 "F.Adhes" user "F.Adhesive")
		(11 "B.Adhes" user "B.Adhesive")
		(13 "F.Paste" user "Package Geometry/Pastemask Top")
		(15 "B.Paste" user "Package Geometry/Pastemask Bottom")
		(5 "F.SilkS" user "Ref Des/Silkscreen Top")
		(7 "B.SilkS" user "Ref Des/Silkscreen Bottom")
		(1 "F.Mask" user "Board Geometry/Soldermask Top")
		(3 "B.Mask" user "Board Geometry/Soldermask Bottom")
		(17 "Dwgs.User" user "User.Drawings")
		(19 "Cmts.User" user "User.Comments")
		(21 "Eco1.User" user "User.Eco1")
		(23 "Eco2.User" user "User.Eco2")
		(25 "Edge.Cuts" user "Board Geometry/Outline")
		(27 "Margin" user)
		(31 "F.CrtYd" user "Package Geometry/Place Bound Top")
		(29 "B.CrtYd" user "Package Geometry/Place Bound Bottom")
		(35 "F.Fab" user "Ref Des/Assembly Top")
		(33 "B.Fab" user "Ref Des/Assembly Bottom")
	)
	(footprint ""
		(layer "F.Cu")
		(at 71.7296 -238.255556 90)
		(property "Reference" "R6640"
			(at 0 0 90)
			(layer "F.SilkS")
			(hide yes)
			(effects
				(font
					(size 1.27 1.27)
				)
			)
		)
		(property "Value" ""
			(at 0 0 90)
			(layer "F.Fab")
			(effects
				(font
					(size 1.27 1.27)
				)
			)
		)
		(duplicate_pad_numbers_are_jumpers no)
		(fp_line
			(start 0.7874 -0.4064)
			(end 0.7874 0.4064)
			(stroke
				(width 0.1524)
				(type default)
			)
			(layer "F.SilkS")
		)
		(fp_line
			(start -0.7874 -0.4064)
			(end 0.7874 -0.4064)
			(stroke
				(width 0.1524)
				(type default)
			)
			(layer "F.SilkS")
		)
		(fp_line
			(start 0.7874 0.4064)
			(end -0.7874 0.4064)
			(stroke
				(width 0.1524)
				(type default)
			)
			(layer "F.SilkS")
		)
		(fp_line
			(start -0.7874 0.4064)
			(end -0.7874 -0.4064)
			(stroke
				(width 0.1524)
				(type default)
			)
			(layer "F.SilkS")
		)
		(fp_line
			(start -0.12065 -0.305054)
			(end -0.12065 -0.2794)
			(stroke
				(width 0.1)
				(type default)
			)
			(layer "F.Fab")
		)
		(fp_line
			(start -0.67945 -0.305054)
			(end -0.12065 -0.305054)
			(stroke
				(width 0.1)
				(type default)
			)
			(layer "F.Fab")
		)
		(fp_line
			(start 0.67945 -0.3048)
			(end 0.67945 0.3048)
			(stroke
				(width 0.1)
				(type default)
			)
			(layer "F.Fab")
		)
		(fp_line
			(start 0.12065 -0.3048)
			(end 0.67945 -0.3048)
			(stroke
				(width 0.1)
				(type default)
			)
			(layer "F.Fab")
		)
		(fp_line
			(start 0.12065 -0.2794)
			(end 0.12065 -0.3048)
			(stroke
				(width 0.1)
				(type default)
			)
			(layer "F.Fab")
		)
		(fp_line
			(start -0.12065 -0.2794)
			(end 0.12065 -0.2794)
			(stroke
				(width 0.1)
				(type default)
			)
			(layer "F.Fab")
		)
		(fp_line
			(start 0.120396 0.2794)
			(end -0.12065 0.2794)
			(stroke
				(width 0.1)
				(type default)
			)
			(layer "F.Fab")
		)
		(fp_line
			(start -0.12065 0.2794)
			(end -0.12065 0.3048)
			(stroke
				(width 0.1)
				(type default)
			)
			(layer "F.Fab")
		)
		(fp_line
			(start 0.67945 0.3048)
			(end 0.120396 0.3048)
			(stroke
				(width 0.1)
				(type default)
			)
			(layer "F.Fab")
		)
		(fp_line
			(start 0.120396 0.3048)
			(end 0.120396 0.2794)
			(stroke
				(width 0.1)
				(type default)
			)
			(layer "F.Fab")
		)
		(fp_line
			(start -0.12065 0.3048)
			(end -0.67945 0.3048)
			(stroke
				(width 0.1)
				(type default)
			)
			(layer "F.Fab")
		)
		(fp_line
			(start -0.67945 0.3048)
			(end -0.67945 -0.305054)
			(stroke
				(width 0.1)
				(type default)
			)
			(layer "F.Fab")
		)
		(pad "1" smd circle
			(at -0.40005 0 90)
			(size 0 0)
			(layers "F.Cu" "F.Mask" "F.Paste")
			(net "UART_PEX0_CLI_BUF_R_TX")
		)
		(pad "2" smd circle
			(at 0.40005 0 90)
			(size 0 0)
			(layers "F.Cu" "F.Mask" "F.Paste")
			(net "UART_PEX0_CLI_BUF_R1_TX")
		)
	)
	(footprint ""
		(layer "F.Cu")
		(at 266.410948 -61.386974)
		(property "Reference" "R4502"
			(at 0 0 0)
			(layer "F.SilkS")
			(hide yes)
			(effects
				(font
					(size 1.27 1.27)
				)
			)
		)
		(property "Value" ""
			(at 0 0 0)
			(layer "F.Fab")
			(effects
				(font
					(size 1.27 1.27)
				)
			)
		)
		(duplicate_pad_numbers_are_jumpers no)
		(fp_line
			(start -0.7874 -0.4064)
			(end 0.7874 -0.4064)
			(stroke
				(width 0.1524)
				(type default)
			)
			(layer "F.SilkS")
		)
		(fp_line
			(start -0.7874 0.4064)
			(end -0.7874 -0.4064)
			(stroke
				(width 0.1524)
				(type default)
			)
			(layer "F.SilkS")
		)
		(fp_line
			(start 0.7874 -0.4064)
			(end 0.7874 0.4064)
			(stroke
				(width 0.1524)
				(type default)
			)
			(layer "F.SilkS")
		)
		(fp_line
			(start 0.7874 0.4064)
			(end -0.7874 0.4064)
			(stroke
				(width 0.1524)
				(type default)
			)
			(layer "F.SilkS")
		)
		(fp_line
			(start -0.67945 -0.305054)
			(end -0.12065 -0.305054)
			(stroke
				(width 0.1)
				(type default)
			)
			(layer "F.Fab")
		)
		(fp_line
			(start -0.67945 0.3048)
			(end -0.67945 -0.305054)
			(stroke
				(width 0.1)
				(type default)
			)
			(layer "F.Fab")
		)
		(fp_line
			(start -0.12065 -0.305054)
			(end -0.12065 -0.2794)
			(stroke
				(width 0.1)
				(type default)
			)
			(layer "F.Fab")
		)
		(fp_line
			(start -0.12065 -0.2794)
			(end 0.12065 -0.2794)
			(stroke
				(width 0.1)
				(type default)
			)
			(layer "F.Fab")
		)
		(fp_line
			(start -0.12065 0.2794)
			(end -0.12065 0.3048)
			(stroke
				(width 0.1)
				(type default)
			)
			(layer "F.Fab")
		)
		(fp_line
			(start -0.12065 0.3048)
			(end -0.67945 0.3048)
			(stroke
				(width 0.1)
				(type default)
			)
			(layer "F.Fab")
		)
		(fp_line
			(start 0.120396 0.2794)
			(end -0.12065 0.2794)
			(stroke
				(width 0.1)
				(type default)
			)
			(layer "F.Fab")
		)
		(fp_line
			(start 0.120396 0.3048)
			(end 0.120396 0.2794)
			(stroke
				(width 0.1)
				(type default)
			)
			(layer "F.Fab")
		)
		(fp_line
			(start 0.12065 -0.3048)
			(end 0.67945 -0.3048)
			(stroke
				(width 0.1)
				(type default)
			)
			(layer "F.Fab")
		)
		(fp_line
			(start 0.12065 -0.2794)
			(end 0.12065 -0.3048)
			(stroke
				(width 0.1)
				(type default)
			)
			(layer "F.Fab")
		)
		(fp_line
			(start 0.67945 -0.3048)
			(end 0.67945 0.3048)
			(stroke
				(width 0.1)
				(type default)
			)
			(layer "F.Fab")
		)
		(fp_line
			(start 0.67945 0.3048)
			(end 0.120396 0.3048)
			(stroke
				(width 0.1)
				(type default)
			)
			(layer "F.Fab")
		)
		(pad "1" smd circle
			(at -0.40005 0)
			(size 0 0)
			(layers "F.Cu" "F.Mask" "F.Paste")
			(net "PWRGD_P3V3_SSD9")
		)
		(pad "2" smd circle
			(at 0.40005 0)
			(size 0 0)
			(layers "F.Cu" "F.Mask" "F.Paste")
			(net "PWRGD_P3V3_SSD9_R")
		)
	)
	(footprint ""
		(layer "F.Cu")
		(at 147.07997 -310.28894 -135)
		(property "Reference" "R1264"
			(at 0 0 225)
			(layer "F.SilkS")
			(hide yes)
			(effects
				(font
					(size 1.27 1.27)
				)
			)
		)
		(property "Value" ""
			(at 0 0 225)
			(layer "F.Fab")
			(effects
				(font
					(size 1.27 1.27)
				)
			)
		)
		(duplicate_pad_numbers_are_jumpers no)
		(fp_line
			(start 0.787389 0.406267)
			(end -0.787389 0.406267)
			(stroke
				(width 0.1524)
				(type default)
			)
			(layer "F.SilkS")
		)
		(fp_line
			(start 0.787389 -0.406267)
			(end 0.787389 0.406267)
			(stroke
				(width 0.1524)
				(type default)
			)
			(layer "F.SilkS")
		)
		(fp_line
			(start -0.787389 0.406267)
			(end -0.787389 -0.406267)
			(stroke
				(width 0.1524)
				(type default)
			)
			(layer "F.SilkS")
		)
		(fp_line
			(start -0.787389 -0.406267)
			(end 0.787389 -0.406267)
			(stroke
				(width 0.1524)
				(type default)
			)
			(layer "F.SilkS")
		)
		(fp_line
			(start 0.679446 0.30479)
			(end 0.120515 0.30479)
			(stroke
				(width 0.1)
				(type default)
			)
			(layer "F.Fab")
		)
		(fp_line
			(start 0.120515 0.30479)
			(end 0.120335 0.279466)
			(stroke
				(width 0.1)
				(type default)
			)
			(layer "F.Fab")
		)
		(fp_line
			(start 0.120335 0.279466)
			(end -0.120695 0.279466)
			(stroke
				(width 0.1)
				(type default)
			)
			(layer "F.Fab")
		)
		(fp_line
			(start 0.679446 -0.30479)
			(end 0.679446 0.30479)
			(stroke
				(width 0.1)
				(type default)
			)
			(layer "F.Fab")
		)
		(fp_line
			(start -0.120515 0.30479)
			(end -0.679446 0.30479)
			(stroke
				(width 0.1)
				(type default)
			)
			(layer "F.Fab")
		)
		(fp_line
			(start -0.120695 0.279466)
			(end -0.120515 0.30479)
			(stroke
				(width 0.1)
				(type default)
			)
			(layer "F.Fab")
		)
		(fp_line
			(start 0.120695 -0.279466)
			(end 0.120515 -0.30479)
			(stroke
				(width 0.1)
				(type default)
			)
			(layer "F.Fab")
		)
		(fp_line
			(start 0.120515 -0.30479)
			(end 0.679446 -0.30479)
			(stroke
				(width 0.1)
				(type default)
			)
			(layer "F.Fab")
		)
		(fp_line
			(start -0.679446 0.30479)
			(end -0.679446 -0.305149)
			(stroke
				(width 0.1)
				(type default)
			)
			(layer "F.Fab")
		)
		(fp_line
			(start -0.120695 -0.279466)
			(end 0.120695 -0.279466)
			(stroke
				(width 0.1)
				(type default)
			)
			(layer "F.Fab")
		)
		(fp_line
			(start -0.120695 -0.304969)
			(end -0.120695 -0.279466)
			(stroke
				(width 0.1)
				(type default)
			)
			(layer "F.Fab")
		)
		(fp_line
			(start -0.679446 -0.305149)
			(end -0.120695 -0.304969)
			(stroke
				(width 0.1)
				(type default)
			)
			(layer "F.Fab")
		)
		(pad "1" smd circle
			(at -0.40005 0 225)
			(size 0 0)
			(layers "F.Cu" "F.Mask" "F.Paste")
			(net "PEX1_DBG_MODE0")
		)
		(pad "2" smd circle
			(at 0.40005 0 225)
			(size 0 0)
			(layers "F.Cu" "F.Mask" "F.Paste")
			(net "P1V8_PEX")
		)
	)
	(footprint ""
		(layer "F.Cu")
		(at 12.383516 -160.327848 180)
		(property "Reference" "PR6869"
			(at 0 0 180)
			(layer "F.SilkS")
			(hide yes)
			(effects
				(font
					(size 1.27 1.27)
				)
			)
		)
		(property "Value" ""
			(at 0 0 180)
			(layer "F.Fab")
			(effects
				(font
					(size 1.27 1.27)
				)
			)
		)
		(duplicate_pad_numbers_are_jumpers no)
		(fp_line
			(start 0.7874 0.4064)
			(end -0.7874 0.4064)
			(stroke
				(width 0.1524)
				(type default)
			)
			(layer "F.SilkS")
		)
		(fp_line
			(start 0.7874 -0.4064)
			(end 0.7874 0.4064)
			(stroke
				(width 0.1524)
				(type default)
			)
			(layer "F.SilkS")
		)
		(fp_line
			(start -0.7874 0.4064)
			(end -0.7874 -0.4064)
			(stroke
				(width 0.1524)
				(type default)
			)
			(layer "F.SilkS")
		)
		(fp_line
			(start -0.7874 -0.4064)
			(end 0.7874 -0.4064)
			(stroke
				(width 0.1524)
				(type default)
			)
			(layer "F.SilkS")
		)
		(fp_line
			(start 0.67945 0.3048)
			(end 0.120396 0.3048)
			(stroke
				(width 0.1)
				(type default)
			)
			(layer "F.Fab")
		)
		(fp_line
			(start 0.67945 -0.3048)
			(end 0.67945 0.3048)
			(stroke
				(width 0.1)
				(type default)
			)
			(layer "F.Fab")
		)
		(fp_line
			(start 0.12065 -0.2794)
			(end 0.12065 -0.3048)
			(stroke
				(width 0.1)
				(type default)
			)
			(layer "F.Fab")
		)
		(fp_line
			(start 0.12065 -0.3048)
			(end 0.67945 -0.3048)
			(stroke
				(width 0.1)
				(type default)
			)
			(layer "F.Fab")
		)
		(fp_line
			(start 0.120396 0.3048)
			(end 0.120396 0.2794)
			(stroke
				(width 0.1)
				(type default)
			)
			(layer "F.Fab")
		)
		(fp_line
			(start 0.120396 0.2794)
			(end -0.12065 0.2794)
			(stroke
				(width 0.1)
				(type default)
			)
			(layer "F.Fab")
		)
		(fp_line
			(start -0.12065 0.3048)
			(end -0.67945 0.3048)
			(stroke
				(width 0.1)
				(type default)
			)
			(layer "F.Fab")
		)
		(fp_line
			(start -0.12065 0.2794)
			(end -0.12065 0.3048)
			(stroke
				(width 0.1)
				(type default)
			)
			(layer "F.Fab")
		)
		(fp_line
			(start -0.12065 -0.2794)
			(end 0.12065 -0.2794)
			(stroke
				(width 0.1)
				(type default)
			)
			(layer "F.Fab")
		)
		(fp_line
			(start -0.12065 -0.305054)
			(end -0.12065 -0.2794)
			(stroke
				(width 0.1)
				(type default)
			)
			(layer "F.Fab")
		)
		(fp_line
			(start -0.67945 0.3048)
			(end -0.67945 -0.305054)
			(stroke
				(width 0.1)
				(type default)
			)
			(layer "F.Fab")
		)
		(fp_line
			(start -0.67945 -0.305054)
			(end -0.12065 -0.305054)
			(stroke
				(width 0.1)
				(type default)
			)
			(layer "F.Fab")
		)
		(pad "1" smd circle
			(at -0.40005 0 180)
			(size 0 0)
			(layers "F.Cu" "F.Mask" "F.Paste")
			(net "P12V_NIC0_CO_ISET")
		)
		(pad "2" smd circle
			(at 0.40005 0 180)
			(size 0 0)
			(layers "F.Cu" "F.Mask" "F.Paste")
			(net "P12V_NIC0_CO_ISET_R")
		)
	)
	(footprint ""
		(layer "F.Cu")
		(at 88.65235 -114.384836 180)
		(property "Reference" "PC667"
			(at 0 0 180)
			(layer "F.SilkS")
			(hide yes)
			(effects
				(font
					(size 1.27 1.27)
				)
			)
		)
		(property "Value" ""
			(at 0 0 180)
			(layer "F.Fab")
			(effects
				(font
					(size 1.27 1.27)
				)
			)
		)
		(duplicate_pad_numbers_are_jumpers no)
		(fp_line
			(start 0.7874 0.4064)
			(end -0.7874 0.4064)
			(stroke
				(width 0.1524)
				(type default)
			)
			(layer "F.SilkS")
		)
		(fp_line
			(start 0.7874 -0.4064)
			(end 0.7874 0.4064)
			(stroke
				(width 0.1524)
				(type default)
			)
			(layer "F.SilkS")
		)
		(fp_line
			(start -0.7874 0.4064)
			(end -0.7874 -0.4064)
			(stroke
				(width 0.1524)
				(type default)
			)
			(layer "F.SilkS")
		)
		(fp_line
			(start -0.7874 -0.4064)
			(end 0.7874 -0.4064)
			(stroke
				(width 0.1524)
				(type default)
			)
			(layer "F.SilkS")
		)
		(fp_line
			(start 0.67945 0.3048)
			(end 0.120396 0.3048)
			(stroke
				(width 0.1)
				(type default)
			)
			(layer "F.Fab")
		)
		(fp_line
			(start 0.67945 -0.3048)
			(end 0.67945 0.3048)
			(stroke
				(width 0.1)
				(type default)
			)
			(layer "F.Fab")
		)
		(fp_line
			(start 0.12065 -0.2794)
			(end 0.12065 -0.3048)
			(stroke
				(width 0.1)
				(type default)
			)
			(layer "F.Fab")
		)
		(fp_line
			(start 0.12065 -0.3048)
			(end 0.67945 -0.3048)
			(stroke
				(width 0.1)
				(type default)
			)
			(layer "F.Fab")
		)
		(fp_line
			(start 0.120396 0.3048)
			(end 0.120396 0.2794)
			(stroke
				(width 0.1)
				(type default)
			)
			(layer "F.Fab")
		)
		(fp_line
			(start 0.120396 0.2794)
			(end -0.12065 0.2794)
			(stroke
				(width 0.1)
				(type default)
			)
			(layer "F.Fab")
		)
		(fp_line
			(start -0.12065 0.3048)
			(end -0.67945 0.3048)
			(stroke
				(width 0.1)
				(type default)
			)
			(layer "F.Fab")
		)
		(fp_line
			(start -0.12065 0.2794)
			(end -0.12065 0.3048)
			(stroke
				(width 0.1)
				(type default)
			)
			(layer "F.Fab")
		)
		(fp_line
			(start -0.12065 -0.2794)
			(end 0.12065 -0.2794)
			(stroke
				(width 0.1)
				(type default)
			)
			(layer "F.Fab")
		)
		(fp_line
			(start -0.12065 -0.305054)
			(end -0.12065 -0.2794)
			(stroke
				(width 0.1)
				(type default)
			)
			(layer "F.Fab")
		)
		(fp_line
			(start -0.67945 0.3048)
			(end -0.67945 -0.305054)
			(stroke
				(width 0.1)
				(type default)
			)
			(layer "F.Fab")
		)
		(fp_line
			(start -0.67945 -0.305054)
			(end -0.12065 -0.305054)
			(stroke
				(width 0.1)
				(type default)
			)
			(layer "F.Fab")
		)
		(pad "1" smd circle
			(at -0.40005 0 180)
			(size 0 0)
			(layers "F.Cu" "F.Mask" "F.Paste")
			(net "P3V3_NIC1_CO_DV_DT")
		)
		(pad "2" smd circle
			(at 0.40005 0 180)
			(size 0 0)
			(layers "F.Cu" "F.Mask" "F.Paste")
			(net "GND")
		)
	)
	(footprint ""
		(layer "F.Cu")
		(at 224.022158 -79.595472 180)
		(property "Reference" "R4348"
			(at 0 0 180)
			(layer "F.SilkS")
			(hide yes)
			(effects
				(font
					(size 1.27 1.27)
				)
			)
		)
		(property "Value" ""
			(at 0 0 180)
			(layer "F.Fab")
			(effects
				(font
					(size 1.27 1.27)
				)
			)
		)
		(duplicate_pad_numbers_are_jumpers no)
		(fp_line
			(start 0.7874 0.4064)
			(end -0.7874 0.4064)
			(stroke
				(width 0.1524)
				(type default)
			)
			(layer "F.SilkS")
		)
		(fp_line
			(start 0.7874 -0.4064)
			(end 0.7874 0.4064)
			(stroke
				(width 0.1524)
				(type default)
			)
			(layer "F.SilkS")
		)
		(fp_line
			(start -0.7874 0.4064)
			(end -0.7874 -0.4064)
			(stroke
				(width 0.1524)
				(type default)
			)
			(layer "F.SilkS")
		)
		(fp_line
			(start -0.7874 -0.4064)
			(end 0.7874 -0.4064)
			(stroke
				(width 0.1524)
				(type default)
			)
			(layer "F.SilkS")
		)
		(fp_line
			(start 0.67945 0.3048)
			(end 0.120396 0.3048)
			(stroke
				(width 0.1)
				(type default)
			)
			(layer "F.Fab")
		)
		(fp_line
			(start 0.67945 -0.3048)
			(end 0.67945 0.3048)
			(stroke
				(width 0.1)
				(type default)
			)
			(layer "F.Fab")
		)
		(fp_line
			(start 0.12065 -0.2794)
			(end 0.12065 -0.3048)
			(stroke
				(width 0.1)
				(type default)
			)
			(layer "F.Fab")
		)
		(fp_line
			(start 0.12065 -0.3048)
			(end 0.67945 -0.3048)
			(stroke
				(width 0.1)
				(type default)
			)
			(layer "F.Fab")
		)
		(fp_line
			(start 0.120396 0.3048)
			(end 0.120396 0.2794)
			(stroke
				(width 0.1)
				(type default)
			)
			(layer "F.Fab")
		)
		(fp_line
			(start 0.120396 0.2794)
			(end -0.12065 0.2794)
			(stroke
				(width 0.1)
				(type default)
			)
			(layer "F.Fab")
		)
		(fp_line
			(start -0.12065 0.3048)
			(end -0.67945 0.3048)
			(stroke
				(width 0.1)
				(type default)
			)
			(layer "F.Fab")
		)
		(fp_line
			(start -0.12065 0.2794)
			(end -0.12065 0.3048)
			(stroke
				(width 0.1)
				(type default)
			)
			(layer "F.Fab")
		)
		(fp_line
			(start -0.12065 -0.2794)
			(end 0.12065 -0.2794)
			(stroke
				(width 0.1)
				(type default)
			)
			(layer "F.Fab")
		)
		(fp_line
			(start -0.12065 -0.305054)
			(end -0.12065 -0.2794)
			(stroke
				(width 0.1)
				(type default)
			)
			(layer "F.Fab")
		)
		(fp_line
			(start -0.67945 0.3048)
			(end -0.67945 -0.305054)
			(stroke
				(width 0.1)
				(type default)
			)
			(layer "F.Fab")
		)
		(fp_line
			(start -0.67945 -0.305054)
			(end -0.12065 -0.305054)
			(stroke
				(width 0.1)
				(type default)
			)
			(layer "F.Fab")
		)
		(pad "1" smd circle
			(at -0.40005 0 180)
			(size 0 0)
			(layers "F.Cu" "F.Mask" "F.Paste")
			(net "P3V3_AUX")
		)
		(pad "2" smd circle
			(at 0.40005 0 180)
			(size 0 0)
			(layers "F.Cu" "F.Mask" "F.Paste")
			(net "SSD10_LED_R")
		)
	)
)
